(kicad_pcb
	(version 20260206)
	(generator "pcbnew")
	(generator_version "10.0")
	(general
		(thickness 1.6)
		(legacy_teardrops no)
	)
	(paper "A4")
	(title_block
		(title "peb — Lightning_PEB_BRD.brd")
		(comment 1 "Lightning (Wiwynn / Facebook NVMe JBOF) / footprints 1013-1019 of 2563")
	)
	(layers
		(0 "F.Cu" signal "TOP")
		(4 "In1.Cu" signal "L2GND")
		(6 "In2.Cu" signal "L3")
		(8 "In3.Cu" signal "L4VCC")
		(10 "In4.Cu" signal "L5VCC")
		(12 "In5.Cu" signal "L6")
		(14 "In6.Cu" signal "L7GND")
		(2 "B.Cu" signal "BOTTOM")
		(9 "F.Adhes" user "F.Adhesive")
		(11 "B.Adhes" user "B.Adhesive")
		(13 "F.Paste" user "Package Geometry/Pastemask Top")
		(15 "B.Paste" user "Package Geometry/Pastemask Bottom")
		(5 "F.SilkS" user "Ref Des/Silkscreen Top")
		(7 "B.SilkS" user "Ref Des/Silkscreen Bottom")
		(1 "F.Mask" user "Board Geometry/Soldermask Top")
		(3 "B.Mask" user "Board Geometry/Soldermask Bottom")
		(17 "Dwgs.User" user "User.Drawings")
		(19 "Cmts.User" user "User.Comments")
		(21 "Eco1.User" user "User.Eco1")
		(23 "Eco2.User" user "User.Eco2")
		(25 "Edge.Cuts" user "Board Geometry/Outline")
		(27 "Margin" user)
		(31 "F.CrtYd" user "Package Geometry/Place Bound Top")
		(29 "B.CrtYd" user "Package Geometry/Place Bound Bottom")
		(35 "F.Fab" user "Ref Des/Assembly Top")
		(33 "B.Fab" user "Ref Des/Assembly Bottom")
	)
	(footprint ""
		(layer "F.Cu")
		(at 129.008124 -196.443092)
		(property "Reference" "R7968"
			(at 0 0 0)
			(layer "F.SilkS")
			(hide yes)
			(effects
				(font
					(size 1.27 1.27)
				)
			)
		)
		(property "Value" "0R2J-2-GP"
			(at 0.064008 -3.993896 0)
			(unlocked yes)
			(layer "F.Fab")
			(hide yes)
			(effects
				(font
					(size 1.016 1.016)
					(thickness 0.1524)
				)
			)
		)
		(property "Device Type" "R402H16"
			(at 0.064008 -5.517896 0)
			(unlocked yes)
			(layer "F.Fab")
			(hide yes)
			(effects
				(font
					(size 1.016 1.016)
					(thickness 0.1524)
				)
			)
		)
		(duplicate_pad_numbers_are_jumpers no)
		(fp_line
			(start -0.508 -0.9398)
			(end -0.508 0.9398)
			(stroke
				(width 0.1524)
				(type default)
			)
			(layer "F.SilkS")
		)
		(fp_line
			(start 0.508 -0.9398)
			(end -0.508 -0.9398)
			(stroke
				(width 0.1524)
				(type default)
			)
			(layer "F.SilkS")
		)
		(fp_rect
			(start -0.508 0.9398)
			(end 0.508 -0.9398)
			(stroke
				(width 0)
				(type default)
			)
			(fill no)
			(layer "F.CrtYd")
		)
		(fp_rect
			(start -0.508 0.9398)
			(end 0.508 -0.9398)
			(stroke
				(width 0)
				(type default)
			)
			(fill no)
			(layer "F.Fab")
		)
		(pad "1" smd custom
			(at 0 -0.4445)
			(size 0.1397 0.1397)
			(layers "F.Cu" "F.Mask" "F.Paste")
			(net "SSD_PERST#1")
			(options
				(clearance outline)
				(anchor circle)
			)
			(primitives
				(gr_poly
					(pts
						(arc
							(start -0.1778 -0.2794)
							(mid -0.249642 -0.249642)
							(end -0.2794 -0.1778)
						)
						(arc
							(start -0.2794 0.1778)
							(mid -0.249642 0.249642)
							(end -0.1778 0.2794)
						)
						(arc
							(start 0.1778 0.2794)
							(mid 0.249642 0.249642)
							(end 0.2794 0.1778)
						)
						(arc
							(start 0.2794 -0.1778)
							(mid 0.249642 -0.249642)
							(end 0.1778 -0.2794)
						)
					)
					(width 0)
					(fill yes)
				)
			)
		)
		(pad "2" smd custom
			(at 0 0.4445)
			(size 0.1397 0.1397)
			(layers "F.Cu" "F.Mask" "F.Paste")
			(net "SSD_PERST#1_R")
			(options
				(clearance outline)
				(anchor circle)
			)
			(primitives
				(gr_poly
					(pts
						(arc
							(start -0.1778 -0.2794)
							(mid -0.249642 -0.249642)
							(end -0.2794 -0.1778)
						)
						(arc
							(start -0.2794 0.1778)
							(mid -0.249642 0.249642)
							(end -0.1778 0.2794)
						)
						(arc
							(start 0.1778 0.2794)
							(mid 0.249642 0.249642)
							(end 0.2794 0.1778)
						)
						(arc
							(start 0.2794 -0.1778)
							(mid 0.249642 -0.249642)
							(end 0.1778 -0.2794)
						)
					)
					(width 0)
					(fill yes)
				)
			)
		)
	)
	(footprint ""
		(layer "F.Cu")
		(at 329.213718 -33.433258)
		(property "Reference" "C53"
			(at 0 0 0)
			(layer "F.SilkS")
			(hide yes)
			(effects
				(font
					(size 1.27 1.27)
				)
			)
		)
		(property "Value" "SCD22U10V2KX-1GP"
			(at 1.1811 -2.7051 0)
			(unlocked yes)
			(layer "F.Fab")
			(hide yes)
			(effects
				(font
					(size 1.016 1.016)
					(thickness 0.1524)
				)
			)
		)
		(property "Device Type" "C402H22"
			(at 1.1811 -4.2291 0)
			(unlocked yes)
			(layer "F.Fab")
			(hide yes)
			(effects
				(font
					(size 1.016 1.016)
					(thickness 0.1524)
				)
			)
		)
		(duplicate_pad_numbers_are_jumpers no)
		(fp_rect
			(start -0.4318 0.9525)
			(end 0.4318 -0.9525)
			(stroke
				(width 0)
				(type default)
			)
			(fill no)
			(layer "F.CrtYd")
		)
		(fp_rect
			(start -0.4318 0.9525)
			(end 0.4318 -0.9525)
			(stroke
				(width 0)
				(type default)
			)
			(fill no)
			(layer "F.Fab")
		)
		(pad "1" smd custom
			(at 0 -0.4445)
			(size 0.1524 0.1524)
			(layers "F.Cu" "F.Mask" "F.Paste")
			(net "PCIE_TX_CAP_N15")
			(options
				(clearance outline)
				(anchor circle)
			)
			(primitives
				(gr_poly
					(pts
						(arc
							(start 0.3048 -0.2032)
							(mid 0.275042 -0.275042)
							(end 0.2032 -0.3048)
						)
						(arc
							(start -0.2032 -0.3048)
							(mid -0.275042 -0.275042)
							(end -0.3048 -0.2032)
						)
						(arc
							(start -0.3048 0.2032)
							(mid -0.275042 0.275042)
							(end -0.2032 0.3048)
						)
						(arc
							(start 0.2032 0.3048)
							(mid 0.275042 0.275042)
							(end 0.3048 0.2032)
						)
					)
					(width 0)
					(fill yes)
				)
			)
		)
		(pad "2" smd custom
			(at 0 0.4445)
			(size 0.1524 0.1524)
			(layers "F.Cu" "F.Mask" "F.Paste")
			(net "PCIE_TX_N15")
			(options
				(clearance outline)
				(anchor circle)
			)
			(primitives
				(gr_poly
					(pts
						(arc
							(start 0.3048 -0.2032)
							(mid 0.275042 -0.275042)
							(end 0.2032 -0.3048)
						)
						(arc
							(start -0.2032 -0.3048)
							(mid -0.275042 -0.275042)
							(end -0.3048 -0.2032)
						)
						(arc
							(start -0.3048 0.2032)
							(mid -0.275042 0.275042)
							(end -0.2032 0.3048)
						)
						(arc
							(start 0.2032 0.3048)
							(mid 0.275042 0.275042)
							(end 0.3048 0.2032)
						)
					)
					(width 0)
					(fill yes)
				)
			)
		)
	)
	(footprint ""
		(layer "F.Cu")
		(at 23.4696 -52.2224 180)
		(property "Reference" "R512"
			(at 0 0 180)
			(layer "F.SilkS")
			(hide yes)
			(effects
				(font
					(size 1.27 1.27)
				)
			)
		)
		(property "Value" "0R2J-2-GP"
			(at 0.064008 -3.993896 180)
			(unlocked yes)
			(layer "F.Fab")
			(hide yes)
			(effects
				(font
					(size 1.016 1.016)
					(thickness 0.1524)
				)
			)
		)
		(property "Device Type" "R402H16"
			(at 0.064008 -5.517896 180)
			(unlocked yes)
			(layer "F.Fab")
			(hide yes)
			(effects
				(font
					(size 1.016 1.016)
					(thickness 0.1524)
				)
			)
		)
		(duplicate_pad_numbers_are_jumpers no)
		(fp_line
			(start 0.508 -0.9398)
			(end -0.508 -0.9398)
			(stroke
				(width 0.1524)
				(type default)
			)
			(layer "F.SilkS")
		)
		(fp_line
			(start -0.508 -0.9398)
			(end -0.508 0.9398)
			(stroke
				(width 0.1524)
				(type default)
			)
			(layer "F.SilkS")
		)
		(fp_rect
			(start -0.508 0.9398)
			(end 0.508 -0.9398)
			(stroke
				(width 0)
				(type default)
			)
			(fill no)
			(layer "F.CrtYd")
		)
		(fp_rect
			(start -0.508 0.9398)
			(end 0.508 -0.9398)
			(stroke
				(width 0)
				(type default)
			)
			(fill no)
			(layer "F.Fab")
		)
		(pad "1" smd custom
			(at 0 -0.4445 180)
			(size 0.1397 0.1397)
			(layers "F.Cu" "F.Mask" "F.Paste")
			(net "NIC0_MDI0_P3_R")
			(options
				(clearance outline)
				(anchor circle)
			)
			(primitives
				(gr_poly
					(pts
						(arc
							(start -0.1778 -0.2794)
							(mid -0.249642 -0.249642)
							(end -0.2794 -0.1778)
						)
						(arc
							(start -0.2794 0.1778)
							(mid -0.249642 0.249642)
							(end -0.1778 0.2794)
						)
						(arc
							(start 0.1778 0.2794)
							(mid 0.249642 0.249642)
							(end 0.2794 0.1778)
						)
						(arc
							(start 0.2794 -0.1778)
							(mid 0.249642 -0.249642)
							(end 0.1778 -0.2794)
						)
					)
					(width 0)
					(fill yes)
				)
			)
		)
		(pad "2" smd custom
			(at 0 0.4445 180)
			(size 0.1397 0.1397)
			(layers "F.Cu" "F.Mask" "F.Paste")
			(net "NIC0_MDI0_P3")
			(options
				(clearance outline)
				(anchor circle)
			)
			(primitives
				(gr_poly
					(pts
						(arc
							(start -0.1778 -0.2794)
							(mid -0.249642 -0.249642)
							(end -0.2794 -0.1778)
						)
						(arc
							(start -0.2794 0.1778)
							(mid -0.249642 0.249642)
							(end -0.1778 0.2794)
						)
						(arc
							(start 0.1778 0.2794)
							(mid 0.249642 0.249642)
							(end 0.2794 0.1778)
						)
						(arc
							(start 0.2794 -0.1778)
							(mid 0.249642 -0.249642)
							(end 0.1778 -0.2794)
						)
					)
					(width 0)
					(fill yes)
				)
			)
		)
	)
	(footprint ""
		(layer "F.Cu")
		(at 181.63794 -14.18844 -90)
		(property "Reference" "R304"
			(at 0 0 270)
			(layer "F.SilkS")
			(hide yes)
			(effects
				(font
					(size 1.27 1.27)
				)
			)
		)
		(property "Value" "0R2J-2-GP"
			(at 0.064008 -3.993896 270)
			(unlocked yes)
			(layer "F.Fab")
			(hide yes)
			(effects
				(font
					(size 1.016 1.016)
					(thickness 0.1524)
				)
			)
		)
		(property "Device Type" "R402H16"
			(at 0.064008 -5.517896 270)
			(unlocked yes)
			(layer "F.Fab")
			(hide yes)
			(effects
				(font
					(size 1.016 1.016)
					(thickness 0.1524)
				)
			)
		)
		(duplicate_pad_numbers_are_jumpers no)
		(fp_line
			(start -0.508 -0.9398)
			(end -0.508 0.9398)
			(stroke
				(width 0.1524)
				(type default)
			)
			(layer "F.SilkS")
		)
		(fp_line
			(start 0.508 -0.9398)
			(end -0.508 -0.9398)
			(stroke
				(width 0.1524)
				(type default)
			)
			(layer "F.SilkS")
		)
		(fp_rect
			(start -0.508 0.9398)
			(end 0.508 -0.9398)
			(stroke
				(width 0)
				(type default)
			)
			(fill no)
			(layer "F.CrtYd")
		)
		(fp_rect
			(start -0.508 0.9398)
			(end 0.508 -0.9398)
			(stroke
				(width 0)
				(type default)
			)
			(fill no)
			(layer "F.Fab")
		)
		(pad "1" smd custom
			(at 0 -0.4445 270)
			(size 0.1397 0.1397)
			(layers "F.Cu" "F.Mask" "F.Paste")
			(net "CLK_P_4_R")
			(options
				(clearance outline)
				(anchor circle)
			)
			(primitives
				(gr_poly
					(pts
						(arc
							(start -0.1778 -0.2794)
							(mid -0.249642 -0.249642)
							(end -0.2794 -0.1778)
						)
						(arc
							(start -0.2794 0.1778)
							(mid -0.249642 0.249642)
							(end -0.1778 0.2794)
						)
						(arc
							(start 0.1778 0.2794)
							(mid 0.249642 0.249642)
							(end 0.2794 0.1778)
						)
						(arc
							(start 0.2794 -0.1778)
							(mid 0.249642 -0.249642)
							(end 0.1778 -0.2794)
						)
					)
					(width 0)
					(fill yes)
				)
			)
		)
		(pad "2" smd custom
			(at 0 0.4445 270)
			(size 0.1397 0.1397)
			(layers "F.Cu" "F.Mask" "F.Paste")
			(net "CLK_P_4")
			(options
				(clearance outline)
				(anchor circle)
			)
			(primitives
				(gr_poly
					(pts
						(arc
							(start -0.1778 -0.2794)
							(mid -0.249642 -0.249642)
							(end -0.2794 -0.1778)
						)
						(arc
							(start -0.2794 0.1778)
							(mid -0.249642 0.249642)
							(end -0.1778 0.2794)
						)
						(arc
							(start 0.1778 0.2794)
							(mid 0.249642 0.249642)
							(end 0.2794 0.1778)
						)
						(arc
							(start 0.2794 -0.1778)
							(mid 0.249642 -0.249642)
							(end 0.1778 -0.2794)
						)
					)
					(width 0)
					(fill yes)
				)
			)
		)
	)
	(footprint ""
		(layer "F.Cu")
		(at 257.423412 -12.473686 90)
		(property "Reference" "R30"
			(at 0 0 90)
			(layer "F.SilkS")
			(hide yes)
			(effects
				(font
					(size 1.27 1.27)
				)
			)
		)
		(property "Value" "4K7R2F-GP"
			(at 0.064008 -3.993896 90)
			(unlocked yes)
			(layer "F.Fab")
			(hide yes)
			(effects
				(font
					(size 1.016 1.016)
					(thickness 0.1524)
				)
			)
		)
		(property "Device Type" "R402H16"
			(at 0.064008 -5.517896 90)
			(unlocked yes)
			(layer "F.Fab")
			(hide yes)
			(effects
				(font
					(size 1.016 1.016)
					(thickness 0.1524)
				)
			)
		)
		(duplicate_pad_numbers_are_jumpers no)
		(fp_line
			(start 0.508 -0.9398)
			(end -0.508 -0.9398)
			(stroke
				(width 0.1524)
				(type default)
			)
			(layer "F.SilkS")
		)
		(fp_line
			(start -0.508 -0.9398)
			(end -0.508 0.9398)
			(stroke
				(width 0.1524)
				(type default)
			)
			(layer "F.SilkS")
		)
		(fp_rect
			(start -0.508 0.9398)
			(end 0.508 -0.9398)
			(stroke
				(width 0)
				(type default)
			)
			(fill no)
			(layer "F.CrtYd")
		)
		(fp_rect
			(start -0.508 0.9398)
			(end 0.508 -0.9398)
			(stroke
				(width 0)
				(type default)
			)
			(fill no)
			(layer "F.Fab")
		)
		(pad "1" smd custom
			(at 0 -0.4445 90)
			(size 0.1397 0.1397)
			(layers "F.Cu" "F.Mask" "F.Paste")
			(net "THERM_EMIT")
			(options
				(clearance outline)
				(anchor circle)
			)
			(primitives
				(gr_poly
					(pts
						(arc
							(start -0.1778 -0.2794)
							(mid -0.249642 -0.249642)
							(end -0.2794 -0.1778)
						)
						(arc
							(start -0.2794 0.1778)
							(mid -0.249642 0.249642)
							(end -0.1778 0.2794)
						)
						(arc
							(start 0.1778 0.2794)
							(mid 0.249642 0.249642)
							(end 0.2794 0.1778)
						)
						(arc
							(start 0.2794 -0.1778)
							(mid 0.249642 -0.249642)
							(end 0.1778 -0.2794)
						)
					)
					(width 0)
					(fill yes)
				)
			)
		)
		(pad "2" smd custom
			(at 0 0.4445 90)
			(size 0.1397 0.1397)
			(layers "F.Cu" "F.Mask" "F.Paste")
			(net "GND")
			(options
				(clearance outline)
				(anchor circle)
			)
			(primitives
				(gr_poly
					(pts
						(arc
							(start -0.1778 -0.2794)
							(mid -0.249642 -0.249642)
							(end -0.2794 -0.1778)
						)
						(arc
							(start -0.2794 0.1778)
							(mid -0.249642 0.249642)
							(end -0.1778 0.2794)
						)
						(arc
							(start 0.1778 0.2794)
							(mid 0.249642 0.249642)
							(end 0.2794 0.1778)
						)
						(arc
							(start 0.2794 -0.1778)
							(mid 0.249642 -0.249642)
							(end 0.1778 -0.2794)
						)
					)
					(width 0)
					(fill yes)
				)
			)
		)
	)
	(footprint ""
		(layer "F.Cu")
		(at 152.20823 -212.420454 180)
		(property "Reference" "C260"
			(at 0 0 180)
			(layer "F.SilkS")
			(hide yes)
			(effects
				(font
					(size 1.27 1.27)
				)
			)
		)
		(property "Value" "SCD22U10V2KX-1GP"
			(at 1.1811 -2.7051 180)
			(unlocked yes)
			(layer "F.Fab")
			(hide yes)
			(effects
				(font
					(size 1.016 1.016)
					(thickness 0.1524)
				)
			)
		)
		(property "Device Type" "C402H22"
			(at 1.1811 -4.2291 180)
			(unlocked yes)
			(layer "F.Fab")
			(hide yes)
			(effects
				(font
					(size 1.016 1.016)
					(thickness 0.1524)
				)
			)
		)
		(duplicate_pad_numbers_are_jumpers no)
		(fp_rect
			(start -0.4318 0.9525)
			(end 0.4318 -0.9525)
			(stroke
				(width 0)
				(type default)
			)
			(fill no)
			(layer "F.CrtYd")
		)
		(fp_rect
			(start -0.4318 0.9525)
			(end 0.4318 -0.9525)
			(stroke
				(width 0)
				(type default)
			)
			(fill no)
			(layer "F.Fab")
		)
		(pad "1" smd custom
			(at 0 -0.4445 180)
			(size 0.1524 0.1524)
			(layers "F.Cu" "F.Mask" "F.Paste")
			(net "PCIE_TX_CAP_N55")
			(options
				(clearance outline)
				(anchor circle)
			)
			(primitives
				(gr_poly
					(pts
						(arc
							(start 0.3048 -0.2032)
							(mid 0.275042 -0.275042)
							(end 0.2032 -0.3048)
						)
						(arc
							(start -0.2032 -0.3048)
							(mid -0.275042 -0.275042)
							(end -0.3048 -0.2032)
						)
						(arc
							(start -0.3048 0.2032)
							(mid -0.275042 0.275042)
							(end -0.2032 0.3048)
						)
						(arc
							(start 0.2032 0.3048)
							(mid 0.275042 0.275042)
							(end 0.3048 0.2032)
						)
					)
					(width 0)
					(fill yes)
				)
			)
		)
		(pad "2" smd custom
			(at 0 0.4445 180)
			(size 0.1524 0.1524)
			(layers "F.Cu" "F.Mask" "F.Paste")
			(net "PCIE_TX_N55")
			(options
				(clearance outline)
				(anchor circle)
			)
			(primitives
				(gr_poly
					(pts
						(arc
							(start 0.3048 -0.2032)
							(mid 0.275042 -0.275042)
							(end 0.2032 -0.3048)
						)
						(arc
							(start -0.2032 -0.3048)
							(mid -0.275042 -0.275042)
							(end -0.3048 -0.2032)
						)
						(arc
							(start -0.3048 0.2032)
							(mid -0.275042 0.275042)
							(end -0.2032 0.3048)
						)
						(arc
							(start 0.2032 0.3048)
							(mid 0.275042 0.275042)
							(end 0.3048 0.2032)
						)
					)
					(width 0)
					(fill yes)
				)
			)
		)
	)
	(footprint ""
		(layer "F.Cu")
		(at 71.7042 -127.3048)
		(property "Reference" "C279"
			(at 0 0 0)
			(layer "F.SilkS")
			(hide yes)
			(effects
				(font
					(size 1.27 1.27)
				)
			)
		)
		(property "Value" "SCD1U16V2KX-3GP"
			(at 1.1811 -2.7051 0)
			(unlocked yes)
			(layer "F.Fab")
			(hide yes)
			(effects
				(font
					(size 1.016 1.016)
					(thickness 0.1524)
				)
			)
		)
		(property "Device Type" "C402H22"
			(at 1.1811 -4.2291 0)
			(unlocked yes)
			(layer "F.Fab")
			(hide yes)
			(effects
				(font
					(size 1.016 1.016)
					(thickness 0.1524)
				)
			)
		)
		(duplicate_pad_numbers_are_jumpers no)
		(fp_rect
			(start -0.4318 0.9525)
			(end 0.4318 -0.9525)
			(stroke
				(width 0)
				(type default)
			)
			(fill no)
			(layer "F.CrtYd")
		)
		(fp_rect
			(start -0.4318 0.9525)
			(end 0.4318 -0.9525)
			(stroke
				(width 0)
				(type default)
			)
			(fill no)
			(layer "F.Fab")
		)
		(pad "1" smd custom
			(at 0 -0.4445)
			(size 0.1524 0.1524)
			(layers "F.Cu" "F.Mask" "F.Paste")
			(net "P3V3_STBY")
			(options
				(clearance outline)
				(anchor circle)
			)
			(primitives
				(gr_poly
					(pts
						(arc
							(start 0.3048 -0.2032)
							(mid 0.275042 -0.275042)
							(end 0.2032 -0.3048)
						)
						(arc
							(start -0.2032 -0.3048)
							(mid -0.275042 -0.275042)
							(end -0.3048 -0.2032)
						)
						(arc
							(start -0.3048 0.2032)
							(mid -0.275042 0.275042)
							(end -0.2032 0.3048)
						)
						(arc
							(start 0.2032 0.3048)
							(mid 0.275042 0.275042)
							(end 0.3048 0.2032)
						)
					)
					(width 0)
					(fill yes)
				)
			)
		)
		(pad "2" smd custom
			(at 0 0.4445)
			(size 0.1524 0.1524)
			(layers "F.Cu" "F.Mask" "F.Paste")
			(net "GND")
			(options
				(clearance outline)
				(anchor circle)
			)
			(primitives
				(gr_poly
					(pts
						(arc
							(start 0.3048 -0.2032)
							(mid 0.275042 -0.275042)
							(end 0.2032 -0.3048)
						)
						(arc
							(start -0.2032 -0.3048)
							(mid -0.275042 -0.275042)
							(end -0.3048 -0.2032)
						)
						(arc
							(start -0.3048 0.2032)
							(mid -0.275042 0.275042)
							(end -0.2032 0.3048)
						)
						(arc
							(start 0.2032 0.3048)
							(mid 0.275042 0.275042)
							(end 0.3048 0.2032)
						)
					)
					(width 0)
					(fill yes)
				)
			)
		)
	)
)
